#ISCELL
  mstr_misc dns *
  *
#ISCELL
  pure_quanta quanta_title_block_c *
  *
#ISCELL
  standard offpage *
  page192_i211
#ISCELL
  standard offpage *
  page192_i214
#ISCELL
  standard offpage *
  page192_i215
#CELL
  pure_quanta q_res *
  page192_i219
#CELL
  pure_quanta q_res *
  page192_i220
#ISCELL
  pure_quanta_power vcc_core *
  page192_i221
#ISCELL
  pure_quanta_power vcc_core *
  page192_i222
#CELL
  pure_quanta q_res *
  page192_i223
#CELL
  pure_quanta q_res *
  page192_i224
#ISCELL
  pure_quanta_power universal_gnd *
  page192_i226
#CELL
  pure_quanta q_res *
  page192_i227
#CELL
  pure_quanta q_cap *
  page192_i228
#CELL
  pure_quanta q_cap *
  page192_i230
#CELL
  pure_quanta q_cap *
  page192_i245
#CELL
  pure_quanta q_res *
  page192_i246
#CELL
  pure_quanta q_cap *
  page192_i247
#ISCELL
  standard offpage *
  page192_i248
#ISCELL
  standard offpage *
  page192_i253
#ISCELL
  standard offpage *
  page192_i254
#ISCELL
  standard offpage *
  page192_i259
#ISCELL
  standard offpage *
  page192_i260
#CELL
  pure_quanta q_res *
  page192_i271
#CELL
  pure_quanta q_res *
  page192_i273
#CELL
  pure_quanta q_cap *
  page192_i274
#CELL
  pure_quanta q_res *
  page192_i275
#ISCELL
  pure_quanta_power vcc_core *
  page192_i276
#CELL
  pure_quanta q_res *
  page192_i277
#CELL
  pure_quanta q_res *
  page192_i278
#CELL
  pure_quanta q_cap *
  page192_i279
#ISCELL
  pure_quanta_power universal_gnd *
  page192_i280
#CELL
  pure_quanta q_cap *
  page192_i281
#ISCELL
  pure_quanta_power universal_gnd *
  page192_i282
#ISCELL
  pure_quanta_power universal_gnd *
  page192_i284
#ISCELL
  pure_quanta_power universal_gnd *
  page192_i285
#CELL
  pure_quanta q_cap *
  page192_i286
#ISCELL
  standard offpage *
  page192_i291
#ISCELL
  pure_quanta_power universal_gnd *
  page192_i311
#ISCELL
  pure_quanta_power universal_gnd *
  page192_i312
#CELL
  pure_quanta q_cap *
  page192_i319
#CELL
  pure_quanta q_cap *
  page192_i322
#CELL
  pure_quanta q_res *
  page192_i325
#ISCELL
  pure_quanta_power vcc_core *
  page192_i326
#ISCELL
  standard offpage *
  page192_i336
#CELL
  pure_quanta raa229620gnpha0 *
  page192_i339
#ISCELL
  standard offpage *
  page192_i340
#CELL
  pure_quanta q_res *
  page192_i348
#CELL
  pure_quanta q_res *
  page192_i351
#ISCELL
  standard offpage *
  page192_i355
#CELL
  pure_quanta q_res *
  page192_i366
#CELL
  pure_quanta q_res *
  page192_i367
#ISCELL
  standard offpage *
  page192_i368
#ISCELL
  standard offpage *
  page192_i371
#CELL
  pure_quanta q_res *
  page192_i372
#CELL
  pure_quanta q_res *
  page192_i378
#CELL
  pure_quanta q_res *
  page192_i379
#CELL
  pure_quanta q_cap *
  page192_i380
#ISCELL
  pure_quanta_power universal_gnd *
  page192_i381
#ISCELL
  pure_quanta_power vcc_core *
  page192_i382
#ISCELL
  standard offpage *
  page192_i384
#CELL
  pure_quanta q_res *
  page192_i385
#ISCELL
  pure_quanta_power vcc_core *
  page192_i390
#CELL
  pure_quanta mosfet_n *
  page192_i391
#CELL
  pure_quanta q_res *
  page192_i392
#ISCELL
  pure_quanta_power universal_gnd *
  page192_i393
#CELL
  pure_quanta q_res *
  page192_i394
#CELL
  pure_quanta q_res *
  page192_i395
#ISCELL
  standard offpage *
  page192_i396
#CELL
  pure_quanta q_cap *
  page192_i397
#ISCELL
  pure_quanta_power universal_gnd *
  page192_i398
#ISCELL
  pure_quanta_power vcc_core *
  page192_i399
#CELL
  pure_quanta q_cap *
  page192_i400
#ISCELL
  pure_quanta_power universal_gnd *
  page192_i401
#ISCELL
  standard offpage *
  page192_i404
#CELL
  pure_quanta q_res *
  page192_i408
#CELL
  pure_quanta q_res *
  page192_i409
#CELL
  pure_quanta q_res *
  page192_i410
#CELL
  pure_quanta q_res *
  page192_i411
#CELL
  pure_quanta q_res *
  page192_i414
#CELL
  pure_quanta q_res *
  page192_i415
#ISCELL
  pure_quanta_power universal_gnd *
  page192_i416
#ISCELL
  pure_quanta_power vcc_core *
  page192_i417
#ISCELL
  pure_quanta_power universal_gnd *
  page192_i418
#ISCELL
  pure_quanta_power universal_gnd *
  page192_i419
#ISCELL
  pure_quanta_power vcc_core *
  page192_i423
#CELL
  pure_quanta mosfet_pch_gds_esd_protected *
  page192_i424
#ISCELL
  pure_quanta_power universal_gnd *
  page192_i425
#CELL
  pure_quanta q_cap *
  page192_i426
#ISCELL
  pure_quanta_power universal_gnd *
  page192_i427
#CELL
  pure_quanta q_cap *
  page192_i428
#ISCELL
  standard offpage *
  page192_i437
#ISCELL
  standard offpage *
  page192_i438
#CELL
  pure_quanta q_cap *
  page192_i499
#CELL
  pure_quanta q_cap *
  page192_i500
#CELL
  pure_quanta q_cap *
  page192_i501
#CELL
  pure_quanta q_res *
  page192_i502
#ISCELL
  pure_quanta_power vcc_core *
  page192_i503
#CELL
  pure_quanta q_res *
  page192_i504
#ISCELL
  pure_quanta_power universal_gnd *
  page192_i505
#CELL
  pure_quanta q_res *
  page192_i506
#ISCELL
  pure_quanta_power vcc_core *
  page192_i507
#CELL
  pure_quanta q_res *
  page192_i508
#ISCELL
  pure_quanta_power universal_gnd *
  page192_i509
#ISCELL
  standard offpage *
  page192_i512
#ISCELL
  standard offpage *
  page192_i513
#ISCELL
  standard offpage *
  page192_i514
#ISCELL
  standard offpage *
  page192_i517
#ISCELL
  standard offpage *
  page192_i520
#ISCELL
  standard offpage *
  page192_i521
#ISCELL
  standard offpage *
  page192_i522
#ISCELL
  standard offpage *
  page192_i523
#ISCELL
  standard offpage *
  page192_i524
#ISCELL
  standard offpage *
  page192_i525
#ISCELL
  standard offpage *
  page192_i526
#ISCELL
  standard offpage *
  page192_i527
#ISCELL
  standard offpage *
  page192_i532
#ISCELL
  standard offpage *
  page192_i533
#ISCELL
  standard offpage *
  page192_i534
#ISCELL
  standard offpage *
  page192_i535
#ISCELL
  standard offpage *
  page192_i536
#ISCELL
  standard offpage *
  page192_i537
#ISCELL
  standard offpage *
  page192_i538
#ISCELL
  standard offpage *
  page192_i539
#ISCELL
  pure_quanta_power universal_gnd *
  page192_i540
#CELL
  pure_quanta q_res *
  page192_i541
#ISCELL
  pure_quanta_power universal_gnd *
  page192_i542
#CELL
  pure_quanta q_res *
  page192_i543
#ISCELL
  pure_quanta_power universal_gnd *
  page192_i544
#CELL
  pure_quanta q_res *
  page192_i545
